(kicad_pcb
	(version 20260206)
	(generator "pcbnew")
	(generator_version "10.0")
	(general
		(thickness 1.6)
		(legacy_teardrops no)
	)
	(paper "A4")
	(title_block
		(title "Bryce Canyon_F.DPB_16315-1-OCP.brd")
		(comment 1 "Bryce Canyon / footprints 302-308 of 2223")
	)
	(layers
		(0 "F.Cu" signal "TOP")
		(4 "In1.Cu" signal "L2GND")
		(6 "In2.Cu" signal "L3")
		(8 "In3.Cu" signal "L4GND")
		(10 "In4.Cu" signal "L5")
		(12 "In5.Cu" signal "L6VCC")
		(14 "In6.Cu" signal "L7VCC")
		(16 "In7.Cu" signal "L8")
		(18 "In8.Cu" signal "L9GND")
		(20 "In9.Cu" signal "L10")
		(22 "In10.Cu" signal "L11GND")
		(2 "B.Cu" signal "BOTTOM")
		(9 "F.Adhes" user "F.Adhesive")
		(11 "B.Adhes" user "B.Adhesive")
		(13 "F.Paste" user "Package Geometry/Pastemask Top")
		(15 "B.Paste" user "Package Geometry/Pastemask Bottom")
		(5 "F.SilkS" user "Ref Des/Silkscreen Top")
		(7 "B.SilkS" user "Ref Des/Silkscreen Bottom")
		(1 "F.Mask" user "Board Geometry/Soldermask Top")
		(3 "B.Mask" user "Board Geometry/Soldermask Bottom")
		(17 "Dwgs.User" user "User.Drawings")
		(19 "Cmts.User" user "User.Comments")
		(21 "Eco1.User" user "User.Eco1")
		(23 "Eco2.User" user "User.Eco2")
		(25 "Edge.Cuts" user "Board Geometry/Outline")
		(27 "Margin" user)
		(31 "F.CrtYd" user "Package Geometry/Place Bound Top")
		(29 "B.CrtYd" user "Package Geometry/Place Bound Bottom")
		(35 "F.Fab" user "Ref Des/Assembly Top")
		(33 "B.Fab" user "Ref Des/Assembly Bottom")
	)
	(footprint ""
		(layer "F.Cu")
		(at 213.5378 -390.8552 -90)
		(property "Reference" "R13"
			(at 0 0 270)
			(layer "F.SilkS")
			(hide yes)
			(effects
				(font
					(size 1.27 1.27)
				)
			)
		)
		(property "Value" "4K7R2J-2-GP"
			(at 0.064008 -3.993896 270)
			(unlocked yes)
			(layer "F.Fab")
			(hide yes)
			(effects
				(font
					(size 1.016 1.016)
					(thickness 0.1524)
				)
			)
		)
		(property "Device Type" "R402H16"
			(at 0.064008 -5.517896 270)
			(unlocked yes)
			(layer "F.Fab")
			(hide yes)
			(effects
				(font
					(size 1.016 1.016)
					(thickness 0.1524)
				)
			)
		)
		(duplicate_pad_numbers_are_jumpers no)
		(fp_line
			(start -0.508 -0.9398)
			(end -0.508 0.9398)
			(stroke
				(width 0.1524)
				(type default)
			)
			(layer "F.SilkS")
		)
		(fp_line
			(start 0.508 -0.9398)
			(end -0.508 -0.9398)
			(stroke
				(width 0.1524)
				(type default)
			)
			(layer "F.SilkS")
		)
		(fp_rect
			(start -0.508 0.9398)
			(end 0.508 -0.9398)
			(stroke
				(width 0)
				(type default)
			)
			(fill no)
			(layer "F.CrtYd")
		)
		(fp_rect
			(start -0.508 0.9398)
			(end 0.508 -0.9398)
			(stroke
				(width 0)
				(type default)
			)
			(fill no)
			(layer "F.Fab")
		)
		(pad "1" smd custom
			(at 0 -0.4445 270)
			(size 0.1397 0.1397)
			(layers "F.Cu" "F.Mask" "F.Paste")
			(net "P3V3_STBY_B")
			(options
				(clearance outline)
				(anchor circle)
			)
			(primitives
				(gr_poly
					(pts
						(arc
							(start -0.1778 -0.2794)
							(mid -0.249642 -0.249642)
							(end -0.2794 -0.1778)
						)
						(arc
							(start -0.2794 0.1778)
							(mid -0.249642 0.249642)
							(end -0.1778 0.2794)
						)
						(arc
							(start 0.1778 0.2794)
							(mid 0.249642 0.249642)
							(end 0.2794 0.1778)
						)
						(arc
							(start 0.2794 -0.1778)
							(mid 0.249642 -0.249642)
							(end 0.1778 -0.2794)
						)
					)
					(width 0)
					(fill yes)
				)
			)
		)
		(pad "2" smd custom
			(at 0 0.4445 270)
			(size 0.1397 0.1397)
			(layers "F.Cu" "F.Mask" "F.Paste")
			(net "BMC_B_TO_EXP_B_RESET_N")
			(options
				(clearance outline)
				(anchor circle)
			)
			(primitives
				(gr_poly
					(pts
						(arc
							(start -0.1778 -0.2794)
							(mid -0.249642 -0.249642)
							(end -0.2794 -0.1778)
						)
						(arc
							(start -0.2794 0.1778)
							(mid -0.249642 0.249642)
							(end -0.1778 0.2794)
						)
						(arc
							(start 0.1778 0.2794)
							(mid 0.249642 0.249642)
							(end 0.2794 0.1778)
						)
						(arc
							(start 0.2794 -0.1778)
							(mid 0.249642 -0.249642)
							(end 0.1778 -0.2794)
						)
					)
					(width 0)
					(fill yes)
				)
			)
		)
	)
	(footprint ""
		(layer "F.Cu")
		(at 146.630898 -292.778942 -90)
		(property "Reference" "C92"
			(at 0 0 270)
			(layer "F.SilkS")
			(hide yes)
			(effects
				(font
					(size 1.27 1.27)
				)
			)
		)
		(property "Value" "SC1U16V3KX-5GP"
			(at 0 -2.8194 270)
			(unlocked yes)
			(layer "F.Fab")
			(hide yes)
			(effects
				(font
					(size 1.016 1.016)
					(thickness 0.1524)
				)
			)
		)
		(property "Device Type" "C603H36"
			(at 0 -4.3434 270)
			(unlocked yes)
			(layer "F.Fab")
			(hide yes)
			(effects
				(font
					(size 1.016 1.016)
					(thickness 0.1524)
				)
			)
		)
		(duplicate_pad_numbers_are_jumpers no)
		(fp_line
			(start 0.508 0)
			(end -0.508 0)
			(stroke
				(width 0.2032)
				(type default)
			)
			(layer "F.SilkS")
		)
		(fp_rect
			(start -0.5842 1.3335)
			(end 0.5842 -1.3335)
			(stroke
				(width 0)
				(type default)
			)
			(fill no)
			(layer "F.CrtYd")
		)
		(fp_rect
			(start -0.5842 1.3335)
			(end 0.5842 -1.3335)
			(stroke
				(width 0)
				(type default)
			)
			(fill no)
			(layer "F.Fab")
		)
		(pad "1" smd custom
			(at 0 -0.762 270)
			(size 0.2159 0.2159)
			(layers "F.Cu" "F.Mask" "F.Paste")
			(net "P5V_HDD4")
			(options
				(clearance outline)
				(anchor circle)
			)
			(primitives
				(gr_poly
					(pts
						(arc
							(start -0.3302 -0.4318)
							(mid -0.402042 -0.402042)
							(end -0.4318 -0.3302)
						)
						(arc
							(start -0.4318 0.3302)
							(mid -0.402042 0.402042)
							(end -0.3302 0.4318)
						)
						(arc
							(start 0.3302 0.4318)
							(mid 0.402042 0.402042)
							(end 0.4318 0.3302)
						)
						(arc
							(start 0.4318 -0.3302)
							(mid 0.402042 -0.402042)
							(end 0.3302 -0.4318)
						)
					)
					(width 0)
					(fill yes)
				)
			)
		)
		(pad "2" smd custom
			(at 0 0.762 270)
			(size 0.2159 0.2159)
			(layers "F.Cu" "F.Mask" "F.Paste")
			(net "GND")
			(options
				(clearance outline)
				(anchor circle)
			)
			(primitives
				(gr_poly
					(pts
						(arc
							(start -0.3302 -0.4318)
							(mid -0.402042 -0.402042)
							(end -0.4318 -0.3302)
						)
						(arc
							(start -0.4318 0.3302)
							(mid -0.402042 0.402042)
							(end -0.3302 0.4318)
						)
						(arc
							(start 0.3302 0.4318)
							(mid 0.402042 0.402042)
							(end 0.4318 0.3302)
						)
						(arc
							(start 0.4318 -0.3302)
							(mid 0.402042 -0.402042)
							(end 0.3302 -0.4318)
						)
					)
					(width 0)
					(fill yes)
				)
			)
		)
	)
	(footprint ""
		(layer "F.Cu")
		(at 456.674982 -207.79994)
		(property "Reference" ""
			(at 0 0 0)
			(layer "F.SilkS")
			(hide yes)
			(effects
				(font
					(size 1.27 1.27)
				)
			)
		)
		(property "Value" "*"
			(at -8.398764 -8.057642 0)
			(unlocked yes)
			(layer "F.Fab")
			(hide yes)
			(effects
				(font
					(size 1.016 1.016)
					(thickness 0.1524)
				)
			)
		)
		(duplicate_pad_numbers_are_jumpers no)
		(fp_poly
			(pts
				(arc
					(start 7.3152 0)
					(mid 0 7.3152)
					(end -7.3152 0)
				)
				(arc
					(start -7.3152 -5.9944)
					(mid 0 -13.3096)
					(end 7.3152 -5.9944)
				)
			)
			(stroke
				(width 0)
				(type default)
			)
			(fill no)
			(layer "B.CrtYd")
		)
		(fp_poly
			(pts
				(arc
					(start 7.3152 0)
					(mid 0 7.3152)
					(end -7.3152 0)
				)
				(arc
					(start -7.3152 -5.9944)
					(mid 0 -13.3096)
					(end 7.3152 -5.9944)
				)
			)
			(stroke
				(width 0)
				(type default)
			)
			(fill no)
			(layer "F.CrtYd")
		)
		(fp_poly
			(pts
				(arc
					(start 7.3152 0)
					(mid 0 7.3152)
					(end -7.3152 0)
				)
				(arc
					(start -7.3152 -5.9944)
					(mid 0 -13.3096)
					(end 7.3152 -5.9944)
				)
			)
			(stroke
				(width 0)
				(type default)
			)
			(fill no)
			(layer "B.Fab")
		)
		(fp_poly
			(pts
				(arc
					(start 7.3152 0)
					(mid 0 7.3152)
					(end -7.3152 0)
				)
				(arc
					(start -7.3152 -5.9944)
					(mid 0 -13.3096)
					(end 7.3152 -5.9944)
				)
			)
			(stroke
				(width 0)
				(type default)
			)
			(fill no)
			(layer "F.Fab")
		)
		(pad "1" thru_hole oval
			(at 0 0)
			(size 14.0208 20.0152)
			(drill 0.0254
				(offset 0 -2.9972)
			)
			(layers "*.Cu" "*.Mask")
			(remove_unused_layers no)
			(net "Net_98")
			(clearance -1.002284)
			(thermal_gap 0.1524)
			(padstack
				(mode front_inner_back)
				(layer "Inner"
					(shape custom)
					(size 2.928012 2.928012)
					(options
						(anchor circle)
					)
					(primitives
						(gr_poly
							(pts
								(arc
									(start 4.571746 -2.084324)
									(mid 0.000333 7.430372)
									(end -4.571492 -2.084324)
								)
								(arc
									(start -4.571492 -2.084324)
									(mid -3.570296 -3.611977)
									(end -2.875026 -5.30098)
								)
								(arc
									(start -2.875026 -5.30098)
									(mid 0.000217 -7.43089)
									(end 2.87528 -5.30098)
								)
								(arc
									(start 2.87528 -5.30098)
									(mid 3.570511 -3.611956)
									(end 4.571746 -2.084324)
								)
							)
							(width 0)
							(fill yes)
						)
					)
					(clearance 0.1524)
				)
				(layer "B.Cu"
					(shape oval)
					(size 14.0208 20.0152)
					(offset 0 -2.9972)
					(clearance -1.002284)
				)
			)
		)
		(zone
			(layers "F.Cu" "B.Cu" "In1.Cu" "In2.Cu" "In3.Cu" "In4.Cu" "In5.Cu" "In6.Cu"
				"In7.Cu" "In8.Cu" "In9.Cu" "In10.Cu"
			)
			(hatch none 0.5)
			(connect_pads
				(clearance 0)
			)
			(min_thickness 0.25)
			(keepout
				(tracks not_allowed)
				(vias allowed)
				(pads allowed)
				(copperpour not_allowed)
				(footprints allowed)
			)
			(placement
				(enabled no)
				(sheetname "")
			)
			(fill
				(thermal_gap 0.5)
				(thermal_bridge_width 0.5)
				(island_removal_mode 0)
			)
			(polygon
				(pts
					(arc
						(start 449.664582 -213.79434)
						(mid 456.674982 -220.80474)
						(end 463.685382 -213.79434)
					)
					(arc
						(start 463.685382 -207.79994)
						(mid 456.674982 -200.78954)
						(end 449.664582 -207.79994)
					)
				)
			)
		)
	)
	(footprint ""
		(layer "F.Cu")
		(at 117.646196 -163.554918 90)
		(property "Reference" "R487"
			(at 0 0 90)
			(layer "F.SilkS")
			(hide yes)
			(effects
				(font
					(size 1.27 1.27)
				)
			)
		)
		(property "Value" "4K7R2J-2-GP"
			(at 0.064008 -3.993896 90)
			(unlocked yes)
			(layer "F.Fab")
			(hide yes)
			(effects
				(font
					(size 1.016 1.016)
					(thickness 0.1524)
				)
			)
		)
		(property "Device Type" "R402H16"
			(at 0.064008 -5.517896 90)
			(unlocked yes)
			(layer "F.Fab")
			(hide yes)
			(effects
				(font
					(size 1.016 1.016)
					(thickness 0.1524)
				)
			)
		)
		(duplicate_pad_numbers_are_jumpers no)
		(fp_line
			(start 0.508 -0.9398)
			(end -0.508 -0.9398)
			(stroke
				(width 0.1524)
				(type default)
			)
			(layer "F.SilkS")
		)
		(fp_line
			(start -0.508 -0.9398)
			(end -0.508 0.9398)
			(stroke
				(width 0.1524)
				(type default)
			)
			(layer "F.SilkS")
		)
		(fp_rect
			(start -0.508 0.9398)
			(end 0.508 -0.9398)
			(stroke
				(width 0)
				(type default)
			)
			(fill no)
			(layer "F.CrtYd")
		)
		(fp_rect
			(start -0.508 0.9398)
			(end 0.508 -0.9398)
			(stroke
				(width 0)
				(type default)
			)
			(fill no)
			(layer "F.Fab")
		)
		(pad "1" smd custom
			(at 0 -0.4445 90)
			(size 0.1397 0.1397)
			(layers "F.Cu" "F.Mask" "F.Paste")
			(net "SW_PWR_R_HDD15")
			(options
				(clearance outline)
				(anchor circle)
			)
			(primitives
				(gr_poly
					(pts
						(arc
							(start -0.1778 -0.2794)
							(mid -0.249642 -0.249642)
							(end -0.2794 -0.1778)
						)
						(arc
							(start -0.2794 0.1778)
							(mid -0.249642 0.249642)
							(end -0.1778 0.2794)
						)
						(arc
							(start 0.1778 0.2794)
							(mid 0.249642 0.249642)
							(end 0.2794 0.1778)
						)
						(arc
							(start 0.2794 -0.1778)
							(mid 0.249642 -0.249642)
							(end 0.1778 -0.2794)
						)
					)
					(width 0)
					(fill yes)
				)
			)
		)
		(pad "2" smd custom
			(at 0 0.4445 90)
			(size 0.1397 0.1397)
			(layers "F.Cu" "F.Mask" "F.Paste")
			(net "GND")
			(options
				(clearance outline)
				(anchor circle)
			)
			(primitives
				(gr_poly
					(pts
						(arc
							(start -0.1778 -0.2794)
							(mid -0.249642 -0.249642)
							(end -0.2794 -0.1778)
						)
						(arc
							(start -0.2794 0.1778)
							(mid -0.249642 0.249642)
							(end -0.1778 0.2794)
						)
						(arc
							(start 0.1778 0.2794)
							(mid 0.249642 0.249642)
							(end 0.2794 0.1778)
						)
						(arc
							(start 0.2794 -0.1778)
							(mid 0.249642 -0.249642)
							(end 0.1778 -0.2794)
						)
					)
					(width 0)
					(fill yes)
				)
			)
		)
	)
	(footprint ""
		(layer "F.Cu")
		(at 245.824502 -392.726164)
		(property "Reference" "C595"
			(at 0 0 0)
			(layer "F.SilkS")
			(hide yes)
			(effects
				(font
					(size 1.27 1.27)
				)
			)
		)
		(property "Value" "SC1U16V3KX-5GP"
			(at 0 -2.8194 0)
			(unlocked yes)
			(layer "F.Fab")
			(hide yes)
			(effects
				(font
					(size 1.016 1.016)
					(thickness 0.1524)
				)
			)
		)
		(property "Device Type" "C603H36"
			(at 0 -4.3434 0)
			(unlocked yes)
			(layer "F.Fab")
			(hide yes)
			(effects
				(font
					(size 1.016 1.016)
					(thickness 0.1524)
				)
			)
		)
		(duplicate_pad_numbers_are_jumpers no)
		(fp_line
			(start 0.508 0)
			(end -0.508 0)
			(stroke
				(width 0.2032)
				(type default)
			)
			(layer "F.SilkS")
		)
		(fp_rect
			(start -0.5842 1.3335)
			(end 0.5842 -1.3335)
			(stroke
				(width 0)
				(type default)
			)
			(fill no)
			(layer "F.CrtYd")
		)
		(fp_rect
			(start -0.5842 1.3335)
			(end 0.5842 -1.3335)
			(stroke
				(width 0)
				(type default)
			)
			(fill no)
			(layer "F.Fab")
		)
		(pad "1" smd custom
			(at 0 -0.762)
			(size 0.2159 0.2159)
			(layers "F.Cu" "F.Mask" "F.Paste")
			(net "MB3_CM_UV_R")
			(options
				(clearance outline)
				(anchor circle)
			)
			(primitives
				(gr_poly
					(pts
						(arc
							(start -0.3302 -0.4318)
							(mid -0.402042 -0.402042)
							(end -0.4318 -0.3302)
						)
						(arc
							(start -0.4318 0.3302)
							(mid -0.402042 0.402042)
							(end -0.3302 0.4318)
						)
						(arc
							(start 0.3302 0.4318)
							(mid 0.402042 0.402042)
							(end 0.4318 0.3302)
						)
						(arc
							(start 0.4318 -0.3302)
							(mid 0.402042 -0.402042)
							(end 0.3302 -0.4318)
						)
					)
					(width 0)
					(fill yes)
				)
			)
		)
		(pad "2" smd custom
			(at 0 0.762)
			(size 0.2159 0.2159)
			(layers "F.Cu" "F.Mask" "F.Paste")
			(net "AGND_CURRENT_DPB")
			(options
				(clearance outline)
				(anchor circle)
			)
			(primitives
				(gr_poly
					(pts
						(arc
							(start -0.3302 -0.4318)
							(mid -0.402042 -0.402042)
							(end -0.4318 -0.3302)
						)
						(arc
							(start -0.4318 0.3302)
							(mid -0.402042 0.402042)
							(end -0.3302 0.4318)
						)
						(arc
							(start 0.3302 0.4318)
							(mid 0.402042 0.402042)
							(end 0.4318 0.3302)
						)
						(arc
							(start 0.4318 -0.3302)
							(mid 0.402042 -0.402042)
							(end 0.3302 -0.4318)
						)
					)
					(width 0)
					(fill yes)
				)
			)
		)
	)
	(footprint ""
		(layer "F.Cu")
		(at 445.0207 -62.143894 90)
		(property "Reference" "R912"
			(at 0 0 90)
			(layer "F.SilkS")
			(hide yes)
			(effects
				(font
					(size 1.27 1.27)
				)
			)
		)
		(property "Value" "10KR2F-2-GP"
			(at 0.064008 -3.993896 90)
			(unlocked yes)
			(layer "F.Fab")
			(hide yes)
			(effects
				(font
					(size 1.016 1.016)
					(thickness 0.1524)
				)
			)
		)
		(property "Device Type" "R402H16"
			(at 0.064008 -5.517896 90)
			(unlocked yes)
			(layer "F.Fab")
			(hide yes)
			(effects
				(font
					(size 1.016 1.016)
					(thickness 0.1524)
				)
			)
		)
		(duplicate_pad_numbers_are_jumpers no)
		(fp_line
			(start 0.508 -0.9398)
			(end -0.508 -0.9398)
			(stroke
				(width 0.1524)
				(type default)
			)
			(layer "F.SilkS")
		)
		(fp_line
			(start -0.508 -0.9398)
			(end -0.508 0.9398)
			(stroke
				(width 0.1524)
				(type default)
			)
			(layer "F.SilkS")
		)
		(fp_rect
			(start -0.508 0.9398)
			(end 0.508 -0.9398)
			(stroke
				(width 0)
				(type default)
			)
			(fill no)
			(layer "F.CrtYd")
		)
		(fp_rect
			(start -0.508 0.9398)
			(end 0.508 -0.9398)
			(stroke
				(width 0)
				(type default)
			)
			(fill no)
			(layer "F.Fab")
		)
		(pad "1" smd custom
			(at 0 -0.4445 90)
			(size 0.1397 0.1397)
			(layers "F.Cu" "F.Mask" "F.Paste")
			(net "P3V3_STBY_A")
			(options
				(clearance outline)
				(anchor circle)
			)
			(primitives
				(gr_poly
					(pts
						(arc
							(start -0.1778 -0.2794)
							(mid -0.249642 -0.249642)
							(end -0.2794 -0.1778)
						)
						(arc
							(start -0.2794 0.1778)
							(mid -0.249642 0.249642)
							(end -0.1778 0.2794)
						)
						(arc
							(start 0.1778 0.2794)
							(mid 0.249642 0.249642)
							(end 0.2794 0.1778)
						)
						(arc
							(start 0.2794 -0.1778)
							(mid 0.249642 -0.249642)
							(end 0.1778 -0.2794)
						)
					)
					(width 0)
					(fill yes)
				)
			)
		)
		(pad "2" smd custom
			(at 0 0.4445 90)
			(size 0.1397 0.1397)
			(layers "F.Cu" "F.Mask" "F.Paste")
			(net "HDD_PRSNT_34")
			(options
				(clearance outline)
				(anchor circle)
			)
			(primitives
				(gr_poly
					(pts
						(arc
							(start -0.1778 -0.2794)
							(mid -0.249642 -0.249642)
							(end -0.2794 -0.1778)
						)
						(arc
							(start -0.2794 0.1778)
							(mid -0.249642 0.249642)
							(end -0.1778 0.2794)
						)
						(arc
							(start 0.1778 0.2794)
							(mid 0.249642 0.249642)
							(end 0.2794 0.1778)
						)
						(arc
							(start 0.2794 -0.1778)
							(mid 0.249642 -0.249642)
							(end 0.1778 -0.2794)
						)
					)
					(width 0)
					(fill yes)
				)
			)
		)
	)
	(footprint ""
		(layer "F.Cu")
		(at 363.655102 -160.252918 -90)
		(property "Reference" "Q115"
			(at 0 0 270)
			(layer "F.SilkS")
			(hide yes)
			(effects
				(font
					(size 1.27 1.27)
				)
			)
		)
		(property "Value" "2N7002KDW-GP"
			(at -2.3622 -8.2042 270)
			(unlocked yes)
			(layer "F.Fab")
			(hide yes)
			(effects
				(font
					(size 1.016 1.016)
					(thickness 0.1524)
				)
			)
		)
		(property "Device Type" "SOT-363H44"
			(at -2.3622 -10.1092 270)
			(unlocked yes)
			(layer "F.Fab")
			(hide yes)
			(effects
				(font
					(size 1.016 1.016)
					(thickness 0.1524)
				)
			)
		)
		(duplicate_pad_numbers_are_jumpers no)
		(fp_line
			(start -1.4478 1.7018)
			(end 1.4478 1.7018)
			(stroke
				(width 0.1524)
				(type default)
			)
			(layer "F.SilkS")
		)
		(fp_line
			(start 1.4478 1.7018)
			(end 1.4478 -1.7018)
			(stroke
				(width 0.1524)
				(type default)
			)
			(layer "F.SilkS")
		)
		(fp_line
			(start -1.27 1.524)
			(end -1.27 0.6604)
			(stroke
				(width 0.4826)
				(type default)
			)
			(layer "F.SilkS")
		)
		(fp_line
			(start -1.4478 -1.7018)
			(end -1.4478 1.7018)
			(stroke
				(width 0.1524)
				(type default)
			)
			(layer "F.SilkS")
		)
		(fp_line
			(start 1.4478 -1.7018)
			(end -1.4478 -1.7018)
			(stroke
				(width 0.1524)
				(type default)
			)
			(layer "F.SilkS")
		)
		(fp_poly
			(pts
				(xy -1.524 -1.778) (xy 1.524 -1.778) (xy 1.524 1.778) (xy -1.524 1.778)
			)
			(stroke
				(width 0)
				(type default)
			)
			(fill no)
			(layer "F.CrtYd")
		)
		(fp_poly
			(pts
				(xy -1.524 -1.778) (xy 1.524 -1.778) (xy 1.524 1.778) (xy -1.524 1.778)
			)
			(stroke
				(width 0)
				(type default)
			)
			(fill no)
			(layer "F.Fab")
		)
		(pad "1" smd rect
			(at -0.65024 0.9398 270)
			(size 0.4064 1.016)
			(layers "F.Cu" "F.Mask" "F.Paste")
			(net "GND")
		)
		(pad "2" smd rect
			(at 0 0.9398 270)
			(size 0.4064 1.016)
			(layers "F.Cu" "F.Mask" "F.Paste")
			(net "SW_PWR_R_HDD19")
		)
		(pad "3" smd rect
			(at 0.65024 0.9398 270)
			(size 0.4064 1.016)
			(layers "F.Cu" "F.Mask" "F.Paste")
			(net "SW_HDD_P19")
		)
		(pad "4" smd rect
			(at 0.65024 -0.9398 270)
			(size 0.4064 1.016)
			(layers "F.Cu" "F.Mask" "F.Paste")
			(net "GND")
		)
		(pad "5" smd rect
			(at 0 -0.9398 270)
			(size 0.4064 1.016)
			(layers "F.Cu" "F.Mask" "F.Paste")
			(net "SW_HDD_G19")
		)
		(pad "6" smd rect
			(at -0.65024 -0.9398 270)
			(size 0.4064 1.016)
			(layers "F.Cu" "F.Mask" "F.Paste")
			(net "SW_HDD_R19")
		)
	)
)
